FILE_TYPE = CONNECTIVITY;
{Allegro Design Entry HDL 16.6-p007 (v16-6-112F) 10/10/2012}
"PAGE_NUMBER" = 123;
0"NC";
1"GND\g";
2"GND\g";
3"PVNN_PCH_STBY\g";
4"PVNN_PCH_STBY\g";
5"P1V05_PCH_STBY\g";
6"VSENSE_PVNN_PCH_STBY_QAT";
7"VSENSE_PVNN_PCH_STBY_FPK";
%"LBG_CORE_QAT_EXT_D"
"11","(-1625,2575)","0","mstr_u_proc","I13";
;
CDS_SEC"11"
ROOM"SB"
CDS_LOCATION"U7C1"
BOM_COST"SB"
CDS_LIB"mstr_u_proc"
SEC"11"
SEC_TYPE"BGA1"
PACK_TYPE"BGA1"
MATERIAL"IC"
PART_NUMBER"H91415-002"
LOCATION"U7C1";
"VSS<494>"
$PN"BP69"2;
"VSS<493>"
$PN"BT69"2;
"VSS<492>"
$PN"BU70"2;
"VSS<491>"
$PN"BR70"2;
"VSS<490>"
$PN"F70"2;
"VSS<489>"
$PN"E70"2;
"VSS<488>"
$PN"BU3"2;
"VSS<487>"
$PN"BR3"2;
"VSS<486>"
$PN"F3"2;
"VSS<485>"
$PN"E3"2;
"VSS<484>"
$PN"A5"2;
"VSS<483>"
$PN"A7"2;
"VSS<482>"
$PN"A9"2;
"VSS<481>"
$PN"A65"2;
"VSS<480>"
$PN"A66"2;
"VSS<479>"
$PN"A68"2;
"VSS<478>"
$PN"J1"2;
"VSS<477>"
$PN"J72"2;
"VSS<476>"
$PN"BN1"2;
"VSS<475>"
$PN"BN72"2;
"VSS<474>"
$PN"CA68"2;
"VSS<473>"
$PN"CA66"2;
"VSS<472>"
$PN"CA65"2;
"VSS<471>"
$PN"CA9"2;
"VSS<470>"
$PN"CA7"2;
"VSS<469>"
$PN"CA5"2;
"VSS<468>"
$PN"A70"2;
"VSS<467>"
$PN"CA3"2;
"VSS<466>"
$PN"BW1"2;
"VSS<465>"
$PN"BU1"2;
"VSS<464>"
$PN"BR1"2;
"VSS<463>"
$PN"C3"2;
"VSS<462>"
$PN"C72"2;
"VSS<461>"
$PN"E1"2;
"VSS<460>"
$PN"E72"2;
"VSS<459>"
$PN"G1"2;
"VSS<458>"
$PN"G72"2;
"VSS<457>"
$PN"BR72"2;
"VSS<456>"
$PN"BU72"2;
"VSS<455>"
$PN"BW70"2;
"VSS<454>"
$PN"BW72"2;
"VSS<453>"
$PN"CA70"2;
"VSS<452>"
$PN"BB48"2;
"VSS<451>"
$PN"AT37"2;
"VSS<450>"
$PN"Y72"2;
"VSS<449>"
$PN"Y70"2;
"VSS<448>"
$PN"A18"2;
"VSS<447>"
$PN"A22"2;
"VSS<446>"
$PN"A30"2;
"VSS<445>"
$PN"A34"2;
"VSS<444>"
$PN"A37"2;
"VSS<443>"
$PN"A41"2;
"VSS<442>"
$PN"B12"2;
"VSS<441>"
$PN"B19"2;
"VSS<440>"
$PN"B25"2;
"VSS<439>"
$PN"B27"2;
"VSS<438>"
$PN"B47"2;
"VSS<437>"
$PN"C22"2;
"VSS<436>"
$PN"C30"2;
"VSS<435>"
$PN"C34"2;
"VSS<434>"
$PN"C37"2;
"VSS<433>"
$PN"C41"2;
"VSS<432>"
$PN"C65"2;
"VSS<431>"
$PN"D12"2;
"VSS<430>"
$PN"D16"2;
"VSS<429>"
$PN"D19"2;
"VSS<428>"
$PN"D25"2;
"VSS<427>"
$PN"D27"2;
"VSS<426>"
$PN"E59"2;
"VSS<425>"
$PN"E65"2;
"VSS<424>"
$PN"D47"1;
"VSS<423>"
$PN"E11"1;
"VSS<422>"
$PN"E13"1;
"VSS<421>"
$PN"E15"1;
"VSS<420>"
$PN"E20"1;
"VSS<419>"
$PN"E22"1;
"VSS<418>"
$PN"E24"1;
"VSS<417>"
$PN"E26"1;
"VSS<416>"
$PN"E28"1;
"VSS<415>"
$PN"E30"1;
"VSS<414>"
$PN"E32"1;
"VSS<413>"
$PN"E34"1;
"VSS<412>"
$PN"E37"1;
"VSS<411>"
$PN"E39"1;
"VSS<410>"
$PN"E41"1;
"VSS<409>"
$PN"E43"1;
"VSS<408>"
$PN"E45"1;
"VSS<407>"
$PN"E48"1;
"VSS<406>"
$PN"E50"1;
"VSS<405>"
$PN"E52"1;
"VSS<404>"
$PN"E54"1;
"VSS<403>"
$PN"E57"1;
"VSS<402>"
$PN"E6"1;
"VSS<401>"
$PN"E61"1;
"VSS<400>"
$PN"E63"1;
"VSS<399>"
$PN"G59"1;
"VSS<398>"
$PN"E9"1;
"VSS<397>"
$PN"G22"1;
"VSS<396>"
$PN"G29"1;
"VSS<395>"
$PN"G37"1;
"VSS<394>"
$PN"G48"1;
"VSS<393>"
$PN"G6"1;
"VSS<392>"
$PN"G63"1;
"VSS<391>"
$PN"G66"1;
"VSS<390>"
$PN"H58"1;
"VSS<389>"
$PN"J29"1;
"VSS<388>"
$PN"J5"1;
"VSS<387>"
$PN"J7"1;
"VSS<386>"
$PN"H65"1;
"VSS<385>"
$PN"J11"1;
"VSS<384>"
$PN"J15"1;
"VSS<383>"
$PN"J22"1;
"VSS<382>"
$PN"J37"1;
"VSS<381>"
$PN"J44"1;
"VSS<380>"
$PN"J59"1;
"VSS<379>"
$PN"J68"1;
"VSS<378>"
$PN"J70"1;
"VSS<377>"
$PN"K54"1;
"VSS<376>"
$PN"K69"1;
"VSS<375>"
$PN"K71"1;
"VSS<374>"
$PN"L5"1;
"VSS<373>"
$PN"L68"1;
"VSS<372>"
$PN"M2"1;
"VSS<371>"
$PN"M22"1;
"VSS<370>"
$PN"M26"1;
"VSS<369>"
$PN"M29"1;
"VSS<368>"
$PN"M33"1;
"VSS<367>"
$PN"M37"1;
"VSS<366>"
$PN"M4"1;
"VSS<365>"
$PN"M40"1;
"VSS<364>"
$PN"N42"1;
"VSS<363>"
$PN"N50"1;
"VSS<362>"
$PN"M44"1;
"VSS<361>"
$PN"M48"1;
"VSS<360>"
$PN"N13"1;
"VSS<359>"
$PN"N17"1;
"VSS<358>"
$PN"N20"1;
"VSS<357>"
$PN"N24"1;
"VSS<356>"
$PN"N27"1;
"VSS<355>"
$PN"N31"1;
%"GND"
"1","(-375,650)","0","mstr_symbols","I14";
;
HDL_POWER"GND"
BODY_TYPE"PLUMBING"
SIZE"1B"
CDS_LIB"mstr_symbols"
VOLTAGE"0.0V";
"A\NAC"1;
%"GND"
"1","(-2800,650)","0","mstr_symbols","I15";
;
HDL_POWER"GND"
BODY_TYPE"PLUMBING"
CDS_LIB"mstr_symbols"
SIZE"1B"
VOLTAGE"0.0V";
"A\NAC"2;
%"PVNN_PCH_STBY"
"1","(-6900,4400)","0","mstr_symbols","I20";
;
HDL_POWER"PVNN_PCH_STBY"
BODY_TYPE"PLUMBING"
CDS_LIB"mstr_symbols"
VOLTAGE"1.0V";
"G\NAC"3;
%"LBG_CORE_QAT_EXT_D"
"10","(-5375,2600)","0","mstr_u_proc","I21";
;
CDS_SEC"10"
ROOM"SB"
CDS_LOCATION"U7C1"
BOM_COST"SB"
CDS_LIB"mstr_u_proc"
SEC"10"
SEC_TYPE"BGA1"
PACK_TYPE"BGA1"
MATERIAL"IC"
PART_NUMBER"H91415-002"
LOCATION"U7C1";
"VCCPRIM_AVID_SENSE"
$PN"AK36"7;
"VCCPRIM_AVID_QAT_SENSE"
$PN"V37"6;
"VCCPRIM_AVID<0>"
$PN"AU36"3;
"VCCPRIM_AVID<1>"
$PN"AU34"3;
"VCCPRIM_AVID<2>"
$PN"AU32"3;
"VCCPRIM_AVID<3>"
$PN"AT36"3;
"VCCPRIM_AVID<4>"
$PN"AT34"3;
"VCCPRIM_AVID<5>"
$PN"AT32"3;
"VCCPRIM_AVID<6>"
$PN"AP39"3;
"VCCPRIM_AVID<7>"
$PN"AP37"3;
"VCCPRIM_AVID<8>"
$PN"AP36"3;
"VCCPRIM_AVID<9>"
$PN"AP34"3;
"VCCPRIM_AVID<10>"
$PN"AP32"3;
"VCCPRIM_AVID<11>"
$PN"AM39"3;
"VCCPRIM_AVID<12>"
$PN"AM37"3;
"VCCPRIM_AVID<13>"
$PN"AM36"3;
"VCCPRIM_AVID<14>"
$PN"AM34"3;
"VCCPRIM_AVID<15>"
$PN"AM32"3;
"VCCPRIM_AVID<16>"
$PN"AK39"3;
"VCCPRIM_AVID<17>"
$PN"AK37"3;
"VCCPRIM_AVID<18>"
$PN"AK34"3;
"VCCPRIM_AVID<19>"
$PN"AG39"3;
"VCCPRIM_AVID<20>"
$PN"AG37"3;
"VCCPRIM_AVID<21>"
$PN"AG36"3;
"VCCPRIM_AVID<22>"
$PN"AG34"3;
"VCCPRIM_AVID<23>"
$PN"AG32"3;
"VCCPRIM_AVID<24>"
$PN"AE41"3;
"VCCPRIM_AVID<25>"
$PN"AE39"3;
"VCCPRIM_AVID<26>"
$PN"AE37"3;
"VCCPRIM_AVID<27>"
$PN"AE36"3;
"VCCPRIM_AVID<28>"
$PN"AE34"3;
"VCCPRIM_AVID<29>"
$PN"AE32"3;
"VCCPRIM_AVID<30>"
$PN"AE30"3;
"VCCPRIM_AVID<31>"
$PN"U27"4;
"VCCPRIM_AVID<32>"
$PN"AC41"3;
"VCCPRIM_AVID<33>"
$PN"AC39"3;
"VCCPRIM_AVID<34>"
$PN"AC37"3;
"VCCPRIM_AVID<35>"
$PN"AC36"3;
"VCCPRIM_AVID<36>"
$PN"AC34"3;
"VCCPRIM_AVID<37>"
$PN"AC32"3;
"VCCPRIM_AVID<38>"
$PN"AC30"3;
"VCCPRIM_AVID<39>"
$PN"AC29"3;
"VCCPRIM_AVID<40>"
$PN"AA41"3;
"VCCPRIM_AVID<41>"
$PN"AA39"3;
"VCCPRIM_AVID<42>"
$PN"AA37"3;
"VCCPRIM_AVID<43>"
$PN"AA36"3;
"VCCPRIM_AVID<44>"
$PN"AA34"3;
"VCCPRIM_AVID<45>"
$PN"AA32"3;
"VCCPRIM_AVID<46>"
$PN"AA30"3;
"VCCPRIM_AVID<47>"
$PN"AA29"3;
"VCCPRIM_AVID<48>"
$PN"Y41"3;
"VCCPRIM_AVID<49>"
$PN"Y39"3;
"VCCPRIM_AVID<50>"
$PN"Y37"3;
"VCCPRIM_AVID<51>"
$PN"Y36"3;
"VCCPRIM_AVID<52>"
$PN"Y34"3;
"VCCPRIM_AVID<53>"
$PN"Y32"3;
"VCCPRIM_AVID<54>"
$PN"Y30"3;
"VCCPRIM_AVID<55>"
$PN"Y29"3;
"VCCPRIM_AVID<56>"
$PN"V40"3;
"VCCPRIM_AVID<57>"
$PN"V33"3;
"VCCPRIM_AVID<58>"
$PN"V29"3;
"VCCPRIM_AVID<59>"
$PN"U38"3;
"VCCPRIM_AVID<60>"
$PN"U35"3;
"VCCPRIM_AVID<61>"
$PN"U31"3;
"VCCPRIM_AVID<62>"
$PN"AK32"4;
"VCCMPHY_1P05<13>"
$PN"AE27"5;
%"PVNN_PCH_STBY"
"1","(-3850,4375)","0","mstr_symbols","I24";
;
HDL_POWER"PVNN_PCH_STBY"
BODY_TYPE"PLUMBING"
CDS_LIB"mstr_symbols"
VOLTAGE"1.0V";
"G\NAC"4;
%"P1V05_PCH_STBY"
"1","(-7425,2800)","0","mstr_symbols","I25";
;
HDL_POWER"P1V05_PCH_STBY"
BODY_TYPE"PLUMBING"
CDS_LIB"mstr_symbols"
VOLTAGE"1.05V";
"G\NAC"5;
END.
